#ISCELL
  mstr_misc dns *
  *
#ISCELL
  pure_quanta quanta_title_block_c *
  *
#ISCELL
  standard offpage *
  page233_i1
#CELL
  pure_quanta q_res *
  page233_i10
#ISCELL
  logical_power universal_gnd *
  page233_i11
#CELL
  pure_quanta conn60_101062636003k02lf *
  page233_i12
#ISCELL
  logical_power universal_gnd *
  page233_i13
#CELL
  pure_quanta q_res *
  page233_i14
#CELL
  pure_quanta q_res *
  page233_i15
#CELL
  pure_quanta ltc4307cms8 *
  page233_i16
#ISCELL
  logical_power universal_gnd *
  page233_i17
#ISCELL
  logical_power universal_power *
  page233_i18
#CELL
  pure_quanta q_cap *
  page233_i19
#ISCELL
  logical_power universal_gnd *
  page233_i2
#CELL
  pure_quanta q_res *
  page233_i20
#CELL
  pure_quanta q_res *
  page233_i21
#CELL
  pure_quanta q_res *
  page233_i22
#ISCELL
  logical_power universal_power *
  page233_i23
#CELL
  pure_quanta q_res *
  page233_i24
#ISCELL
  standard offpage *
  page233_i25
#ISCELL
  standard offpage *
  page233_i26
#ISCELL
  standard offpage *
  page233_i27
#ISCELL
  standard offpage *
  page233_i28
#ISCELL
  standard offpage *
  page233_i29
#CELL
  pure_quanta q_res *
  page233_i3
#ISCELL
  standard offpage *
  page233_i30
#ISCELL
  standard offpage *
  page233_i31
#ISCELL
  standard offpage *
  page233_i32
#ISCELL
  standard offpage *
  page233_i33
#CELL
  pure_quanta q_res *
  page233_i34
#CELL
  pure_quanta q_res *
  page233_i35
#ISCELL
  logical_power universal_power *
  page233_i36
#CELL
  pure_quanta q_res *
  page233_i37
#CELL
  pure_quanta q_res *
  page233_i38
#CELL
  pure_quanta q_res *
  page233_i39
#CELL
  pure_quanta q_res *
  page233_i4
#ISCELL
  standard offpage *
  page233_i40
#CELL
  pure_quanta q_res *
  page233_i41
#ISCELL
  logical_power universal_power *
  page233_i42
#ISCELL
  standard offpage *
  page233_i43
#ISCELL
  standard offpage *
  page233_i44
#ISCELL
  standard offpage *
  page233_i45
#ISCELL
  standard offpage *
  page233_i46
#ISCELL
  standard offpage *
  page233_i47
#ISCELL
  standard offpage *
  page233_i48
#ISCELL
  standard offpage *
  page233_i49
#ISCELL
  logical_power universal_power *
  page233_i5
#ISCELL
  standard offpage *
  page233_i50
#CELL
  pure_quanta q_cap *
  page233_i51
#CELL
  pure_quanta q_cap *
  page233_i52
#CELL
  pure_quanta q_cap *
  page233_i53
#CELL
  pure_quanta q_cap *
  page233_i54
#CELL
  pure_quanta q_cap *
  page233_i55
#ISCELL
  logical_power universal_gnd *
  page233_i56
#CELL
  pure_quanta q_cap *
  page233_i57
#ISCELL
  standard offpage *
  page233_i6
#ISCELL
  standard offpage *
  page233_i7
#CELL
  pure_quanta q_res *
  page233_i8
#CELL
  pure_quanta q_res *
  page233_i9
